(kicad_pcb
	(version 20221018)
	(generator pcbnew)
	(general
    (thickness 1.62)
  )
	(paper "A4")
	(title_block
    (title "ECP5 - Datacenter Secure Control Module (DC-SCM)")
    (date "2024-07-01")
    (rev "1.2.1")
		(comment 9 "footprints 78-79 of 506")
	)
	(layers
    (0 "F.Cu" signal)
    (1 "In1.Cu" power)
    (2 "In2.Cu" signal)
    (3 "In3.Cu" power)
    (4 "In4.Cu" power)
    (5 "In5.Cu" signal)
    (6 "In6.Cu" power)
    (31 "B.Cu" signal)
    (32 "B.Adhes" user "B.Adhesive")
    (33 "F.Adhes" user "F.Adhesive")
    (34 "B.Paste" user)
    (35 "F.Paste" user)
    (36 "B.SilkS" user "B.Silkscreen")
    (37 "F.SilkS" user "F.Silkscreen")
    (38 "B.Mask" user)
    (39 "F.Mask" user)
    (40 "Dwgs.User" user "User.Drawings")
    (41 "Cmts.User" user "User.Comments")
    (42 "Eco1.User" user "User.Eco1")
    (43 "Eco2.User" user "User.Eco2")
    (44 "Edge.Cuts" user)
    (45 "Margin" user)
    (46 "B.CrtYd" user "B.Courtyard")
    (47 "F.CrtYd" user "F.Courtyard")
    (48 "B.Fab" user)
    (49 "F.Fab" user)
  )
	(footprint "antmicro-footprints:C_0402_1005Metric" (layer "F.Cu")
    (at 127.575 168.325 -90)
    (descr "Capacitor SMD 0402")
    (tags "capacitor SMD 0402")
    (property "Author" "Antmicro")
    (property "Dielectric" "X5R")
    (property "License" "Apache-2.0")
    (property "MPN" "GRM155R61H104KE14D")
    (property "Manufacturer" "Murata")
    (property "Public" "False")
    (property "Sheetfile" "pcie-conn.kicad_sch")
    (property "Sheetname" "PCIe-connector")
    (property "Val" "100n")
    (property "Voltage" "50V")
    (property "ki_description" "SMD Multilayer Ceramic Capacitor, 0.1 µF, 50 V, 0402 [1005 Metric], ± 10%, X5R, GRM Series")
    (property "ki_keywords" "0402, SMT, CAPACITOR, PASSIVE, CERAMIC, MLCC")
    (attr smd)
    (fp_text reference "C35" (at 2.14 -0.12 90) (layer "F.SilkS")
        (effects (font (size 0.7 0.7) (thickness 0.127)))
    )
    (fp_text value "C_100n_0402" (at 0 1.17 90) (layer "F.Fab")
        (effects (font (size 1 1) (thickness 0.15)))
    )
    (fp_text user "Author: Antmicro" (at -0.939 3.399 -90) (layer "F.Fab") hide
        (effects (font (size 0.7 0.7) (thickness 0.15)) (justify left bottom))
    )
    (fp_text user "${REFERENCE}" (at 0 0 90) (layer "F.Fab")
        (effects (font (size 0.25 0.25) (thickness 0.04)))
    )
    (fp_text user "License: Apache-2.0" (at -0.939 5.799 -90) (layer "F.Fab") hide
        (effects (font (size 0.7 0.7) (thickness 0.15)) (justify left bottom))
    )
    (fp_rect (start -0.925 -0.47) (end 0.925 0.47)
      (stroke (width 0.05) (type default)) (fill none) (layer "F.CrtYd"))
    (fp_line (start -0.494 -0.25) (end 0.504 -0.25)
      (stroke (width 0.15) (type solid)) (layer "F.Fab"))
    (fp_line (start -0.494 0.248) (end -0.494 -0.25)
      (stroke (width 0.15) (type solid)) (layer "F.Fab"))
    (fp_line (start 0.504 -0.25) (end 0.504 0.248)
      (stroke (width 0.15) (type solid)) (layer "F.Fab"))
    (fp_line (start 0.504 0.248) (end -0.494 0.248)
      (stroke (width 0.15) (type solid)) (layer "F.Fab"))
    (pad "1" smd roundrect (at -0.48 0 270) (size 0.59 0.64) (layers "F.Cu" "F.Paste" "F.Mask") (roundrect_rratio 0.25)
      (net 213 "Net-(J2-PET0_N)") (pintype "passive"))
    (pad "2" smd roundrect (at 0.48 0 270) (size 0.59 0.64) (layers "F.Cu" "F.Paste" "F.Mask") (roundrect_rratio 0.25)
      (net 692 "PCIE_HPM_TX0_N") (pintype "passive"))
  )
	(footprint "antmicro-footprints:C_0402_1005Metric" (layer "F.Cu")
    (at 132.535 168.325 -90)
    (descr "Capacitor SMD 0402")
    (tags "capacitor SMD 0402")
    (property "Author" "Antmicro")
    (property "Dielectric" "X5R")
    (property "License" "Apache-2.0")
    (property "MPN" "GRM155R61H104KE14D")
    (property "Manufacturer" "Murata")
    (property "Public" "False")
    (property "Sheetfile" "pcie-conn.kicad_sch")
    (property "Sheetname" "PCIe-connector")
    (property "Val" "100n")
    (property "Voltage" "50V")
    (property "ki_description" "SMD Multilayer Ceramic Capacitor, 0.1 µF, 50 V, 0402 [1005 Metric], ± 10%, X5R, GRM Series")
    (property "ki_keywords" "0402, SMT, CAPACITOR, PASSIVE, CERAMIC, MLCC")
    (attr smd)
    (fp_text reference "C33" (at 2.14 -0.04 90) (layer "F.SilkS")
        (effects (font (size 0.7 0.7) (thickness 0.127)))
    )
    (fp_text value "C_100n_0402" (at 0 1.17 90) (layer "F.Fab")
        (effects (font (size 1 1) (thickness 0.15)))
    )
    (fp_text user "License: Apache-2.0" (at -0.939 5.799 -90) (layer "F.Fab") hide
        (effects (font (size 0.7 0.7) (thickness 0.15)) (justify left bottom))
    )
    (fp_text user "Author: Antmicro" (at -0.939 3.399 -90) (layer "F.Fab") hide
        (effects (font (size 0.7 0.7) (thickness 0.15)) (justify left bottom))
    )
    (fp_text user "${REFERENCE}" (at 0 0 90) (layer "F.Fab")
        (effects (font (size 0.25 0.25) (thickness 0.04)))
    )
    (fp_rect (start -0.925 -0.47) (end 0.925 0.47)
      (stroke (width 0.05) (type default)) (fill none) (layer "F.CrtYd"))
    (fp_line (start -0.494 -0.25) (end 0.504 -0.25)
      (stroke (width 0.15) (type solid)) (layer "F.Fab"))
    (fp_line (start -0.494 0.248) (end -0.494 -0.25)
      (stroke (width 0.15) (type solid)) (layer "F.Fab"))
    (fp_line (start 0.504 -0.25) (end 0.504 0.248)
      (stroke (width 0.15) (type solid)) (layer "F.Fab"))
    (fp_line (start 0.504 0.248) (end -0.494 0.248)
      (stroke (width 0.15) (type solid)) (layer "F.Fab"))
    (pad "1" smd roundrect (at -0.48 0 270) (size 0.59 0.64) (layers "F.Cu" "F.Paste" "F.Mask") (roundrect_rratio 0.25)
      (net 18 "Net-(J2-PET2_P)") (pintype "passive"))
    (pad "2" smd roundrect (at 0.48 0 270) (size 0.59 0.64) (layers "F.Cu" "F.Paste" "F.Mask") (roundrect_rratio 0.25)
      (net 690 "PCIE_HPM_TX2_P") (pintype "passive"))
  )
)
